# S9S_MB_2U (Grand Teton) — schematic netlist excerpt (pin names and nets, part order shuffled) for the footprints in the layout excerpt that follows; sources: Cadence DE-HDL packaged netlist, KiCad conversion of 03242023_DA0F0TMBIJ0_F0T_Motherboard_J_brd_V01_OCP.brd

C2024  Q_CAP  0.1UF 25V 10% X7R  pkg 0402  page 171 : A = P3V3_OCP_SFF_R ; B = GND
R4265  Q_RES  4.7K 5% EMPTY  pkg 0402LF  page 246 : A = PWRGD_P3V3_AUX_PDB_BUF_R ; B = GND
DM9  DUMMY_SYMBOL  MECHANIC_SYMBOL MECH  pkg TP30_FOR_BOM  page 312 : \1\ = NC
C772  Q_CAP_DIFFBUS  DIFF BUS_0.22UF 6.3V 20% X6S  pkg C0201  page 176 : \1\ = P5E_CPU1_PE2_TX_C_DN<0> ; \2\ = P5E_CPU1_PE2_TX_DN<0>

(kicad_pcb
	(version 20260206)
	(generator "pcbnew")
	(generator_version "10.0")
	(general
		(thickness 1.6)
		(legacy_teardrops no)
	)
	(paper "A4")
	(title_block
		(title "03242023_DA0F0TMBIJ0_F0T_Motherboard_J_brd_V01_OCP.brd")
		(comment 1 "Grand Teton / footprints 2650-2653 of 6105")
	)
	(layers
		(0 "F.Cu" signal "TOP")
		(4 "In1.Cu" signal "GND")
		(6 "In2.Cu" signal "IN1")
		(8 "In3.Cu" signal "GND1")
		(10 "In4.Cu" signal "IN2")
		(12 "In5.Cu" signal "GND2")
		(14 "In6.Cu" signal "IN3")
		(16 "In7.Cu" signal "GND3")
		(18 "In8.Cu" signal "VCC")
		(20 "In9.Cu" signal "VCC1")
		(22 "In10.Cu" signal "GND4")
		(24 "In11.Cu" signal "IN4")
		(26 "In12.Cu" signal "GND5")
		(28 "In13.Cu" signal "IN5")
		(30 "In14.Cu" signal "GND6")
		(32 "In15.Cu" signal "IN6")
		(34 "In16.Cu" signal "GND7")
		(2 "B.Cu" signal "BOTTOM")
		(9 "F.Adhes" user "F.Adhesive")
		(11 "B.Adhes" user "B.Adhesive")
		(13 "F.Paste" user "Package Geometry/Pastemask Top")
		(15 "B.Paste" user "Package Geometry/Pastemask Bottom")
		(5 "F.SilkS" user "Ref Des/Silkscreen Top")
		(7 "B.SilkS" user "Ref Des/Silkscreen Bottom")
		(1 "F.Mask" user "Board Geometry/Soldermask Top")
		(3 "B.Mask" user "Board Geometry/Soldermask Bottom")
		(17 "Dwgs.User" user "User.Drawings")
		(19 "Cmts.User" user "User.Comments")
		(21 "Eco1.User" user "User.Eco1")
		(23 "Eco2.User" user "User.Eco2")
		(25 "Edge.Cuts" user "Board Geometry/Outline")
		(27 "Margin" user)
		(31 "F.CrtYd" user "Package Geometry/Place Bound Top")
		(29 "B.CrtYd" user "Package Geometry/Place Bound Bottom")
		(35 "F.Fab" user "Ref Des/Assembly Top")
		(33 "B.Fab" user "Ref Des/Assembly Bottom")
	)
	(footprint ""
		(layer "F.Cu")
		(at 306.09159 -427.168818 180)
		(property "Reference" "R4265"
			(at 0 0 180)
			(layer "F.SilkS")
			(hide yes)
			(effects
				(font
					(size 1.27 1.27)
				)
			)
		)
		(property "Value" ""
			(at 0 0 180)
			(layer "F.Fab")
			(effects
				(font
					(size 1.27 1.27)
				)
			)
		)
		(duplicate_pad_numbers_are_jumpers no)
		(fp_line
			(start 0.7874 0.4064)
			(end -0.7874 0.4064)
			(stroke
				(width 0.1524)
				(type default)
			)
			(layer "F.SilkS")
		)
		(fp_line
			(start 0.7874 -0.4064)
			(end 0.7874 0.4064)
			(stroke
				(width 0.1524)
				(type default)
			)
			(layer "F.SilkS")
		)
		(fp_line
			(start -0.7874 0.4064)
			(end -0.7874 -0.4064)
			(stroke
				(width 0.1524)
				(type default)
			)
			(layer "F.SilkS")
		)
		(fp_line
			(start -0.7874 -0.4064)
			(end 0.7874 -0.4064)
			(stroke
				(width 0.1524)
				(type default)
			)
			(layer "F.SilkS")
		)
		(fp_line
			(start 0.67945 0.3048)
			(end 0.120396 0.3048)
			(stroke
				(width 0.1)
				(type default)
			)
			(layer "F.Fab")
		)
		(fp_line
			(start 0.67945 -0.3048)
			(end 0.67945 0.3048)
			(stroke
				(width 0.1)
				(type default)
			)
			(layer "F.Fab")
		)
		(fp_line
			(start 0.12065 -0.2794)
			(end 0.12065 -0.3048)
			(stroke
				(width 0.1)
				(type default)
			)
			(layer "F.Fab")
		)
		(fp_line
			(start 0.12065 -0.3048)
			(end 0.67945 -0.3048)
			(stroke
				(width 0.1)
				(type default)
			)
			(layer "F.Fab")
		)
		(fp_line
			(start 0.120396 0.3048)
			(end 0.120396 0.2794)
			(stroke
				(width 0.1)
				(type default)
			)
			(layer "F.Fab")
		)
		(fp_line
			(start 0.120396 0.2794)
			(end -0.12065 0.2794)
			(stroke
				(width 0.1)
				(type default)
			)
			(layer "F.Fab")
		)
		(fp_line
			(start -0.12065 0.3048)
			(end -0.67945 0.3048)
			(stroke
				(width 0.1)
				(type default)
			)
			(layer "F.Fab")
		)
		(fp_line
			(start -0.12065 0.2794)
			(end -0.12065 0.3048)
			(stroke
				(width 0.1)
				(type default)
			)
			(layer "F.Fab")
		)
		(fp_line
			(start -0.12065 -0.2794)
			(end 0.12065 -0.2794)
			(stroke
				(width 0.1)
				(type default)
			)
			(layer "F.Fab")
		)
		(fp_line
			(start -0.12065 -0.305054)
			(end -0.12065 -0.2794)
			(stroke
				(width 0.1)
				(type default)
			)
			(layer "F.Fab")
		)
		(fp_line
			(start -0.67945 0.3048)
			(end -0.67945 -0.305054)
			(stroke
				(width 0.1)
				(type default)
			)
			(layer "F.Fab")
		)
		(fp_line
			(start -0.67945 -0.305054)
			(end -0.12065 -0.305054)
			(stroke
				(width 0.1)
				(type default)
			)
			(layer "F.Fab")
		)
		(pad "1" smd circle
			(at -0.40005 0 180)
			(size 0 0)
			(layers "F.Cu" "F.Mask" "F.Paste")
			(net "PWRGD_P3V3_AUX_PDB_BUF_R")
		)
		(pad "2" smd circle
			(at 0.40005 0 180)
			(size 0 0)
			(layers "F.Cu" "F.Mask" "F.Paste")
			(net "GND")
		)
	)
	(footprint ""
		(layer "F.Cu")
		(at 497.43868 -468.007446)
		(property "Reference" "DM9"
			(at -0.3937 -0.588518 0)
			(unlocked yes)
			(layer "F.SilkS")
			(effects
				(font
					(size 0.254 0.127)
					(thickness 0.000001)
				)
				(justify left)
			)
		)
		(property "Value" ""
			(at 0 0 0)
			(layer "F.Fab")
			(effects
				(font
					(size 1.27 1.27)
				)
			)
		)
		(duplicate_pad_numbers_are_jumpers no)
		(pad "1" smd circle
			(at 0 0)
			(size 0.762 0.762)
			(layers "F.Cu" "F.Mask" "F.Paste")
			(net "Net_8587")
		)
	)
	(footprint ""
		(layer "F.Cu")
		(at 437.515 -94.071948 90)
		(property "Reference" "C2024"
			(at 0 0 90)
			(layer "F.SilkS")
			(hide yes)
			(effects
				(font
					(size 1.27 1.27)
				)
			)
		)
		(property "Value" ""
			(at 0 0 90)
			(layer "F.Fab")
			(effects
				(font
					(size 1.27 1.27)
				)
			)
		)
		(duplicate_pad_numbers_are_jumpers no)
		(fp_line
			(start 0.7874 -0.4064)
			(end 0.7874 0.4064)
			(stroke
				(width 0.1524)
				(type default)
			)
			(layer "F.SilkS")
		)
		(fp_line
			(start -0.7874 -0.4064)
			(end 0.7874 -0.4064)
			(stroke
				(width 0.1524)
				(type default)
			)
			(layer "F.SilkS")
		)
		(fp_line
			(start 0.7874 0.4064)
			(end -0.7874 0.4064)
			(stroke
				(width 0.1524)
				(type default)
			)
			(layer "F.SilkS")
		)
		(fp_line
			(start -0.7874 0.4064)
			(end -0.7874 -0.4064)
			(stroke
				(width 0.1524)
				(type default)
			)
			(layer "F.SilkS")
		)
		(fp_line
			(start -0.12065 -0.305054)
			(end -0.12065 -0.2794)
			(stroke
				(width 0.1)
				(type default)
			)
			(layer "F.Fab")
		)
		(fp_line
			(start -0.67945 -0.305054)
			(end -0.12065 -0.305054)
			(stroke
				(width 0.1)
				(type default)
			)
			(layer "F.Fab")
		)
		(fp_line
			(start 0.67945 -0.3048)
			(end 0.67945 0.3048)
			(stroke
				(width 0.1)
				(type default)
			)
			(layer "F.Fab")
		)
		(fp_line
			(start 0.12065 -0.3048)
			(end 0.67945 -0.3048)
			(stroke
				(width 0.1)
				(type default)
			)
			(layer "F.Fab")
		)
		(fp_line
			(start 0.12065 -0.2794)
			(end 0.12065 -0.3048)
			(stroke
				(width 0.1)
				(type default)
			)
			(layer "F.Fab")
		)
		(fp_line
			(start -0.12065 -0.2794)
			(end 0.12065 -0.2794)
			(stroke
				(width 0.1)
				(type default)
			)
			(layer "F.Fab")
		)
		(fp_line
			(start 0.120396 0.2794)
			(end -0.12065 0.2794)
			(stroke
				(width 0.1)
				(type default)
			)
			(layer "F.Fab")
		)
		(fp_line
			(start -0.12065 0.2794)
			(end -0.12065 0.3048)
			(stroke
				(width 0.1)
				(type default)
			)
			(layer "F.Fab")
		)
		(fp_line
			(start 0.67945 0.3048)
			(end 0.120396 0.3048)
			(stroke
				(width 0.1)
				(type default)
			)
			(layer "F.Fab")
		)
		(fp_line
			(start 0.120396 0.3048)
			(end 0.120396 0.2794)
			(stroke
				(width 0.1)
				(type default)
			)
			(layer "F.Fab")
		)
		(fp_line
			(start -0.12065 0.3048)
			(end -0.67945 0.3048)
			(stroke
				(width 0.1)
				(type default)
			)
			(layer "F.Fab")
		)
		(fp_line
			(start -0.67945 0.3048)
			(end -0.67945 -0.305054)
			(stroke
				(width 0.1)
				(type default)
			)
			(layer "F.Fab")
		)
		(pad "1" smd circle
			(at -0.40005 0 90)
			(size 0 0)
			(layers "F.Cu" "F.Mask" "F.Paste")
			(net "P3V3_OCP_SFF_R")
		)
		(pad "2" smd circle
			(at 0.40005 0 90)
			(size 0 0)
			(layers "F.Cu" "F.Mask" "F.Paste")
			(net "GND")
		)
	)
	(footprint ""
		(layer "F.Cu")
		(at 166.992554 -402.371052 -90)
		(property "Reference" "C772"
			(at 0 0 270)
			(layer "F.SilkS")
			(hide yes)
			(effects
				(font
					(size 1.27 1.27)
				)
			)
		)
		(property "Value" ""
			(at 0 0 270)
			(layer "F.Fab")
			(effects
				(font
					(size 1.27 1.27)
				)
			)
		)
		(duplicate_pad_numbers_are_jumpers no)
		(fp_line
			(start -0.299974 0.150114)
			(end -0.299974 -0.150114)
			(stroke
				(width 0.1)
				(type default)
			)
			(layer "F.Fab")
		)
		(fp_line
			(start 0.299974 0.150114)
			(end -0.299974 0.150114)
			(stroke
				(width 0.1)
				(type default)
			)
			(layer "F.Fab")
		)
		(fp_line
			(start -0.299974 -0.150114)
			(end 0.299974 -0.150114)
			(stroke
				(width 0.1)
				(type default)
			)
			(layer "F.Fab")
		)
		(fp_line
			(start 0.299974 -0.150114)
			(end 0.299974 0.150114)
			(stroke
				(width 0.1)
				(type default)
			)
			(layer "F.Fab")
		)
		(pad "1" smd rect
			(at -0.2667 0 270)
			(size 0.3048 0.381)
			(layers "F.Cu" "F.Mask" "F.Paste")
			(net "P5E_CPU1_PE2_TX_C_DN<0>")
		)
		(pad "2" smd rect
			(at 0.2667 0 270)
			(size 0.3048 0.381)
			(layers "F.Cu" "F.Mask" "F.Paste")
			(net "P5E_CPU1_PE2_TX_DN<0>")
		)
	)
)
